(kicad_pcb
	(version 20241229)
	(generator "pcbnew")
	(generator_version "9.0")
	(general
		(thickness 1.63)
		(legacy_teardrops no)
	)
	(paper "A4")
	(title_block
		(title "CM4 Baseboard")
		(date "2026-01-05")
		(rev "1.1.1")
		(company "Antmicro Ltd")
		(comment 1 "www.antmicro.com")
		(comment 9 "footprints 69-73 of 506")
	)
	(layers
		(0 "F.Cu" signal)
		(4 "In1.Cu" power)
		(6 "In2.Cu" power)
		(8 "In3.Cu" signal)
		(10 "In4.Cu" signal)
		(2 "B.Cu" signal)
		(9 "F.Adhes" user "F.Adhesive")
		(11 "B.Adhes" user "B.Adhesive")
		(13 "F.Paste" user)
		(15 "B.Paste" user)
		(5 "F.SilkS" user "F.Silkscreen")
		(7 "B.SilkS" user "B.Silkscreen")
		(1 "F.Mask" user)
		(3 "B.Mask" user)
		(17 "Dwgs.User" user "User.Drawings")
		(19 "Cmts.User" user "User.Comments")
		(21 "Eco1.User" user "User.Eco1")
		(23 "Eco2.User" user "User.Eco2")
		(25 "Edge.Cuts" user)
		(27 "Margin" user)
		(31 "F.CrtYd" user "F.Courtyard")
		(29 "B.CrtYd" user "B.Courtyard")
		(35 "F.Fab" user)
		(33 "B.Fab" user)
	)
	(footprint "antmicro-footprints:Nexperia_DFN-10_2.5x1mm_P0.5mm"
		(layer "F.Cu")
		(at 109.112462 125.3415)
		(property "Reference" "D707"
			(at -1.3195 1.65 0)
			(layer "F.SilkS")
			(effects
				(font
					(size 0.7 0.7)
					(thickness 0.15)
				)
				(justify left bottom)
			)
		)
		(property "Value" "PUSB3F96X_PASS"
			(at -0.016 1.705 0)
			(layer "F.Fab")
			(effects
				(font
					(size 0.7 0.7)
					(thickness 0.15)
				)
				(justify left bottom)
			)
		)
		(property "Datasheet" "https://mouser.com/datasheet/2/916/PUSB3F96-1600324.pdf"
			(at 0 0 0)
			(layer "F.Fab")
			(hide yes)
			(effects
				(font
					(size 1.27 1.27)
					(thickness 0.15)
				)
			)
		)
		(property "Manufacturer" "Nexperia"
			(at 0 0 0)
			(unlocked yes)
			(layer "F.Fab")
			(hide yes)
			(effects
				(font
					(size 1 1)
					(thickness 0.15)
				)
			)
		)
		(property "MPN" "PUSB3F96X"
			(at 0 0 0)
			(unlocked yes)
			(layer "F.Fab")
			(hide yes)
			(effects
				(font
					(size 1 1)
					(thickness 0.15)
				)
			)
		)
		(property "Author" "Antmicro"
			(at 0 0 0)
			(unlocked yes)
			(layer "F.Fab")
			(hide yes)
			(effects
				(font
					(size 1 1)
					(thickness 0.15)
				)
			)
		)
		(property "License" "Apache-2.0"
			(at 0 0 0)
			(unlocked yes)
			(layer "F.Fab")
			(hide yes)
			(effects
				(font
					(size 1 1)
					(thickness 0.15)
				)
			)
		)
		(sheetname "/Display/")
		(sheetfile "display.kicad_sch")
		(attr smd)
		(fp_line
			(start -1.375 -0.4)
			(end -1.375 0.4)
			(stroke
				(width 0.15)
				(type solid)
			)
			(layer "F.SilkS")
		)
		(fp_line
			(start 1.375 0.4)
			(end 1.375 -0.4)
			(stroke
				(width 0.15)
				(type solid)
			)
			(layer "F.SilkS")
		)
		(fp_circle
			(center -1.4 0.7)
			(end -1.349 0.7)
			(stroke
				(width 0.15)
				(type solid)
			)
			(fill yes)
			(layer "F.SilkS")
		)
		(fp_rect
			(start -1.4 -0.725)
			(end 1.4 0.725)
			(stroke
				(width 0.05)
				(type solid)
			)
			(fill no)
			(layer "F.CrtYd")
		)
		(fp_line
			(start -1.25 -0.5)
			(end -1.25 0.15)
			(stroke
				(width 0.15)
				(type solid)
			)
			(layer "F.Fab")
		)
		(fp_line
			(start -1.25 0.15)
			(end -0.9 0.5)
			(stroke
				(width 0.15)
				(type solid)
			)
			(layer "F.Fab")
		)
		(fp_line
			(start -0.9 0.5)
			(end 1.25 0.5)
			(stroke
				(width 0.15)
				(type solid)
			)
			(layer "F.Fab")
		)
		(fp_line
			(start 1.25 -0.5)
			(end -1.25 -0.5)
			(stroke
				(width 0.15)
				(type solid)
			)
			(layer "F.Fab")
		)
		(fp_line
			(start 1.25 0.5)
			(end 1.25 -0.5)
			(stroke
				(width 0.15)
				(type solid)
			)
			(layer "F.Fab")
		)
		(fp_text user "${REFERENCE}"
			(at -1.367 3.704 0)
			(layer "F.Fab")
			(effects
				(font
					(size 0.7 0.7)
					(thickness 0.15)
				)
				(justify left bottom)
			)
		)
		(fp_text user "Author: Antmicro"
			(at -1.367 4.905 0)
			(layer "F.Fab")
			(effects
				(font
					(size 0.7 0.7)
					(thickness 0.15)
				)
				(justify left bottom)
			)
		)
		(fp_text user "License: Apache-2.0"
			(at -1.367 6.105 0)
			(layer "F.Fab")
			(effects
				(font
					(size 0.7 0.7)
					(thickness 0.15)
				)
				(justify left bottom)
			)
		)
		(pad "1" smd rect
			(at -1 0.3875)
			(size 0.2 0.475)
			(layers "F.Cu" "F.Mask" "F.Paste")
			(net 35 "/Compute module/HDMI.D0_P")
			(pinfunction "CH1")
			(pintype "passive")
			(solder_mask_margin 0.05)
		)
		(pad "2" smd rect
			(at -0.5 0.3875)
			(size 0.2 0.475)
			(layers "F.Cu" "F.Mask" "F.Paste")
			(net 34 "/Compute module/HDMI.D0_N")
			(pinfunction "CH2")
			(pintype "passive")
			(solder_mask_margin 0.05)
		)
		(pad "3" smd rect
			(at 0 0.3875)
			(size 0.2 0.475)
			(layers "F.Cu" "F.Mask" "F.Paste")
			(net 3 "GND")
			(pinfunction "GND")
			(pintype "passive")
			(solder_mask_margin 0.05)
		)
		(pad "4" smd rect
			(at 0.5 0.3875)
			(size 0.2 0.475)
			(layers "F.Cu" "F.Mask" "F.Paste")
			(net 25 "/Compute module/HDMI.CLK_P")
			(pinfunction "CH3")
			(pintype "passive")
			(solder_mask_margin 0.05)
		)
		(pad "5" smd rect
			(at 1 0.3875)
			(size 0.2 0.475)
			(layers "F.Cu" "F.Mask" "F.Paste")
			(net 23 "/Compute module/HDMI.CLK_N")
			(pinfunction "CH4")
			(pintype "passive")
			(solder_mask_margin 0.05)
		)
		(pad "6" smd rect
			(at 1 -0.3875)
			(size 0.2 0.475)
			(layers "F.Cu" "F.Mask" "F.Paste")
			(net 23 "/Compute module/HDMI.CLK_N")
			(pinfunction "CH4")
			(pintype "passive")
			(solder_mask_margin 0.05)
		)
		(pad "7" smd rect
			(at 0.5 -0.3875)
			(size 0.2 0.475)
			(layers "F.Cu" "F.Mask" "F.Paste")
			(net 25 "/Compute module/HDMI.CLK_P")
			(pinfunction "CH3")
			(pintype "passive")
			(solder_mask_margin 0.05)
		)
		(pad "8" smd rect
			(at 0 -0.3875)
			(size 0.2 0.475)
			(layers "F.Cu" "F.Mask" "F.Paste")
			(net 3 "GND")
			(pinfunction "GND")
			(pintype "passive")
			(solder_mask_margin 0.05)
		)
		(pad "9" smd rect
			(at -0.501 -0.3875)
			(size 0.2 0.475)
			(layers "F.Cu" "F.Mask" "F.Paste")
			(net 34 "/Compute module/HDMI.D0_N")
			(pinfunction "CH2")
			(pintype "passive")
			(solder_mask_margin 0.05)
		)
		(pad "10" smd rect
			(at -1 -0.3875)
			(size 0.2 0.475)
			(layers "F.Cu" "F.Mask" "F.Paste")
			(net 35 "/Compute module/HDMI.D0_P")
			(pinfunction "CH1")
			(pintype "passive")
			(solder_mask_margin 0.05)
		)
	)
	(footprint "antmicro-footprints:C_0402_1005Metric"
		(layer "F.Cu")
		(at 86.167962 145.0165)
		(descr "Capacitor SMD 0402")
		(tags "capacitor SMD 0402")
		(property "Reference" "C934"
			(at -3.55 -0.15 0)
			(layer "F.SilkS")
			(effects
				(font
					(size 0.7 0.7)
					(thickness 0.15)
				)
				(justify left bottom)
			)
		)
		(property "Value" "C_100n_0402"
			(at -1.022927 2.155213 0)
			(layer "F.Fab")
			(effects
				(font
					(size 0.7 0.7)
					(thickness 0.15)
				)
				(justify left bottom)
			)
		)
		(property "Datasheet" "https://www.murata.com/products/productdetail?partno=GRM155R61H104KE14%23"
			(at 0 0 0)
			(layer "F.Fab")
			(hide yes)
			(effects
				(font
					(size 1.27 1.27)
					(thickness 0.15)
				)
			)
		)
		(property "MPN" "GRM155R61H104KE14D"
			(at 0 0 0)
			(unlocked yes)
			(layer "F.Fab")
			(hide yes)
			(effects
				(font
					(size 1 1)
					(thickness 0.15)
				)
			)
		)
		(property "Manufacturer" "Murata"
			(at 0 0 0)
			(unlocked yes)
			(layer "F.Fab")
			(hide yes)
			(effects
				(font
					(size 1 1)
					(thickness 0.15)
				)
			)
		)
		(property "License" "Apache-2.0"
			(at 0 0 0)
			(unlocked yes)
			(layer "F.Fab")
			(hide yes)
			(effects
				(font
					(size 1 1)
					(thickness 0.15)
				)
			)
		)
		(property "Author" "Antmicro"
			(at 0 0 0)
			(unlocked yes)
			(layer "F.Fab")
			(hide yes)
			(effects
				(font
					(size 1 1)
					(thickness 0.15)
				)
			)
		)
		(property "Val" "100n"
			(at 0 0 0)
			(unlocked yes)
			(layer "F.Fab")
			(hide yes)
			(effects
				(font
					(size 1 1)
					(thickness 0.15)
				)
			)
		)
		(property "Voltage" "50V"
			(at 0 0 0)
			(unlocked yes)
			(layer "F.Fab")
			(hide yes)
			(effects
				(font
					(size 1 1)
					(thickness 0.15)
				)
			)
		)
		(property "Dielectric" "X5R"
			(at 0 0 0)
			(unlocked yes)
			(layer "F.Fab")
			(hide yes)
			(effects
				(font
					(size 1 1)
					(thickness 0.15)
				)
			)
		)
		(sheetname "/USB/")
		(sheetfile "usb.kicad_sch")
		(attr smd)
		(fp_rect
			(start -0.925 -0.47)
			(end 0.925 0.47)
			(stroke
				(width 0.05)
				(type default)
			)
			(fill no)
			(layer "F.CrtYd")
		)
		(fp_line
			(start -0.494 -0.25)
			(end 0.504 -0.25)
			(stroke
				(width 0.15)
				(type solid)
			)
			(layer "F.Fab")
		)
		(fp_line
			(start -0.494 0.248)
			(end -0.494 -0.25)
			(stroke
				(width 0.15)
				(type solid)
			)
			(layer "F.Fab")
		)
		(fp_line
			(start 0.504 -0.25)
			(end 0.504 0.248)
			(stroke
				(width 0.15)
				(type solid)
			)
			(layer "F.Fab")
		)
		(fp_line
			(start 0.504 0.248)
			(end -0.494 0.248)
			(stroke
				(width 0.15)
				(type solid)
			)
			(layer "F.Fab")
		)
		(fp_text user "${REFERENCE}"
			(at -0.939 4.599 0)
			(layer "F.Fab")
			(effects
				(font
					(size 0.7 0.7)
					(thickness 0.15)
				)
				(justify left bottom)
			)
		)
		(fp_text user "License: Apache-2.0"
			(at -0.939 5.799 0)
			(layer "F.Fab")
			(effects
				(font
					(size 0.7 0.7)
					(thickness 0.15)
				)
				(justify left bottom)
			)
		)
		(fp_text user "Author: Antmicro"
			(at -0.939 3.399 0)
			(layer "F.Fab")
			(effects
				(font
					(size 0.7 0.7)
					(thickness 0.15)
				)
				(justify left bottom)
			)
		)
		(pad "1" smd roundrect
			(at -0.48 0)
			(size 0.59 0.64)
			(layers "F.Cu" "F.Mask" "F.Paste")
			(roundrect_rratio 0.25)
			(net 3 "GND")
			(pintype "passive")
		)
		(pad "2" smd roundrect
			(at 0.48 0)
			(size 0.59 0.64)
			(layers "F.Cu" "F.Mask" "F.Paste")
			(roundrect_rratio 0.25)
			(net 27 "/USB/USB_3V3")
			(pintype "passive")
		)
	)
	(footprint "antmicro-footprints:C_0402_1005Metric"
		(layer "F.Cu")
		(at 100.242962 128.4165)
		(descr "Capacitor SMD 0402")
		(tags "capacitor SMD 0402")
		(property "Reference" "C930"
			(at -0.715 -0.02 90)
			(layer "F.SilkS")
			(effects
				(font
					(size 0.7 0.7)
					(thickness 0.15)
				)
				(justify left bottom)
			)
		)
		(property "Value" "C_100n_0402"
			(at -1.022927 2.155213 0)
			(layer "F.Fab")
			(effects
				(font
					(size 0.7 0.7)
					(thickness 0.15)
				)
				(justify left bottom)
			)
		)
		(property "Datasheet" "https://www.murata.com/products/productdetail?partno=GRM155R61H104KE14%23"
			(at 0 0 0)
			(layer "F.Fab")
			(hide yes)
			(effects
				(font
					(size 1.27 1.27)
					(thickness 0.15)
				)
			)
		)
		(property "Manufacturer" "Murata"
			(at 0 0 0)
			(unlocked yes)
			(layer "F.Fab")
			(hide yes)
			(effects
				(font
					(size 1 1)
					(thickness 0.15)
				)
			)
		)
		(property "MPN" "GRM155R61H104KE14D"
			(at 0 0 0)
			(unlocked yes)
			(layer "F.Fab")
			(hide yes)
			(effects
				(font
					(size 1 1)
					(thickness 0.15)
				)
			)
		)
		(property "Val" "100n"
			(at 0 0 0)
			(unlocked yes)
			(layer "F.Fab")
			(hide yes)
			(effects
				(font
					(size 1 1)
					(thickness 0.15)
				)
			)
		)
		(property "License" "Apache-2.0"
			(at 0 0 0)
			(unlocked yes)
			(layer "F.Fab")
			(hide yes)
			(effects
				(font
					(size 1 1)
					(thickness 0.15)
				)
			)
		)
		(property "Author" "Antmicro"
			(at 0 0 0)
			(unlocked yes)
			(layer "F.Fab")
			(hide yes)
			(effects
				(font
					(size 1 1)
					(thickness 0.15)
				)
			)
		)
		(property "Voltage" "50V"
			(at 0 0 0)
			(unlocked yes)
			(layer "F.Fab")
			(hide yes)
			(effects
				(font
					(size 1 1)
					(thickness 0.15)
				)
			)
		)
		(property "Dielectric" "X5R"
			(at 0 0 0)
			(unlocked yes)
			(layer "F.Fab")
			(hide yes)
			(effects
				(font
					(size 1 1)
					(thickness 0.15)
				)
			)
		)
		(sheetname "/USB/")
		(sheetfile "usb.kicad_sch")
		(attr smd)
		(fp_rect
			(start -0.925 -0.47)
			(end 0.925 0.47)
			(stroke
				(width 0.05)
				(type default)
			)
			(fill no)
			(layer "F.CrtYd")
		)
		(fp_line
			(start -0.494 -0.25)
			(end 0.504 -0.25)
			(stroke
				(width 0.15)
				(type solid)
			)
			(layer "F.Fab")
		)
		(fp_line
			(start -0.494 0.248)
			(end -0.494 -0.25)
			(stroke
				(width 0.15)
				(type solid)
			)
			(layer "F.Fab")
		)
		(fp_line
			(start 0.504 -0.25)
			(end 0.504 0.248)
			(stroke
				(width 0.15)
				(type solid)
			)
			(layer "F.Fab")
		)
		(fp_line
			(start 0.504 0.248)
			(end -0.494 0.248)
			(stroke
				(width 0.15)
				(type solid)
			)
			(layer "F.Fab")
		)
		(fp_text user "${REFERENCE}"
			(at -0.939 4.599 0)
			(layer "F.Fab")
			(effects
				(font
					(size 0.7 0.7)
					(thickness 0.15)
				)
				(justify left bottom)
			)
		)
		(fp_text user "License: Apache-2.0"
			(at -0.939 5.799 0)
			(layer "F.Fab")
			(effects
				(font
					(size 0.7 0.7)
					(thickness 0.15)
				)
				(justify left bottom)
			)
		)
		(fp_text user "Author: Antmicro"
			(at -0.939 3.399 0)
			(layer "F.Fab")
			(effects
				(font
					(size 0.7 0.7)
					(thickness 0.15)
				)
				(justify left bottom)
			)
		)
		(pad "1" smd roundrect
			(at -0.48 0)
			(size 0.59 0.64)
			(layers "F.Cu" "F.Mask" "F.Paste")
			(roundrect_rratio 0.25)
			(net 127 "Net-(Q903-G)")
			(pintype "passive")
		)
		(pad "2" smd roundrect
			(at 0.48 0)
			(size 0.59 0.64)
			(layers "F.Cu" "F.Mask" "F.Paste")
			(roundrect_rratio 0.25)
			(net 28 "/USB/+5V_{CAP}")
			(pintype "passive")
		)
	)
	(footprint "antmicro-footprints:TP_SMD_0.75mm"
		(layer "F.Cu")
		(at 76.967962 166.1415 180)
		(property "Reference" "TP201"
			(at 9.115 0.96 0)
			(layer "F.SilkS")
			(effects
				(font
					(size 0.7 0.7)
					(thickness 0.15)
				)
				(justify right bottom)
			)
		)
		(property "Value" "TP_0.75mm_SMD"
			(at 0 1.2 0)
			(layer "F.Fab")
			(effects
				(font
					(size 0.7 0.7)
					(thickness 0.15)
				)
				(justify right bottom)
			)
		)
		(property "Author" "Antmicro"
			(at 0 0 180)
			(unlocked yes)
			(layer "F.Fab")
			(hide yes)
			(effects
				(font
					(size 1 1)
					(thickness 0.15)
				)
			)
		)
		(property "License" "Apache-2.0"
			(at 0 0 180)
			(unlocked yes)
			(layer "F.Fab")
			(hide yes)
			(effects
				(font
					(size 1 1)
					(thickness 0.15)
				)
			)
		)
		(property "MPN" ""
			(at 0 0 180)
			(unlocked yes)
			(layer "F.Fab")
			(hide yes)
			(effects
				(font
					(size 1 1)
					(thickness 0.15)
				)
			)
		)
		(property "Manufacturer" ""
			(at 0 0 180)
			(unlocked yes)
			(layer "F.Fab")
			(hide yes)
			(effects
				(font
					(size 1 1)
					(thickness 0.15)
				)
			)
		)
		(sheetname "/Compute module/")
		(sheetfile "compute-module.kicad_sch")
		(attr exclude_from_pos_files exclude_from_bom)
		(fp_circle
			(center 0 0)
			(end 0.475 0)
			(stroke
				(width 0.05)
				(type default)
			)
			(fill no)
			(layer "F.CrtYd")
		)
		(fp_text user "Author: Antmicro"
			(at -0.4 3.901 180)
			(layer "F.Fab")
			(effects
				(font
					(size 0.7 0.7)
					(thickness 0.15)
				)
				(justify left bottom)
			)
		)
		(fp_text user "${REFERENCE}"
			(at -0.4 2.7 180)
			(layer "F.Fab")
			(effects
				(font
					(size 0.7 0.7)
					(thickness 0.15)
				)
				(justify left bottom)
			)
		)
		(fp_text user "License: Apache-2.0"
			(at -0.4 5.101 180)
			(layer "F.Fab")
			(effects
				(font
					(size 0.7 0.7)
					(thickness 0.15)
				)
				(justify left bottom)
			)
		)
		(pad "1" smd circle
			(at 0 0 180)
			(size 0.75 0.75)
			(layers "F.Cu" "F.Mask")
			(net 249 "/Compute module/RUN_PG")
			(pinfunction "1")
			(pintype "passive")
		)
	)
	(footprint "antmicro-footprints:R_0402_1005Metric"
		(layer "F.Cu")
		(at 80.017962 168.2415 180)
		(descr "Resistor SMD 0402")
		(tags "resistor SMD 0402")
		(property "Reference" "R215"
			(at -1.34 0.395 0)
			(layer "F.SilkS")
			(effects
				(font
					(size 0.7 0.7)
					(thickness 0.15)
				)
				(justify right bottom)
			)
		)
		(property "Value" "R_2k2_0402"
			(at -1.011843 1.772047 0)
			(layer "F.Fab")
			(effects
				(font
					(size 0.7 0.7)
					(thickness 0.15)
				)
				(justify right bottom)
			)
		)
		(property "Datasheet" "https://www.bourns.com/docs/product-datasheets/cr.pdf"
			(at 0 0 180)
			(layer "F.Fab")
			(hide yes)
			(effects
				(font
					(size 1.27 1.27)
					(thickness 0.15)
				)
			)
		)
		(property "Manufacturer" "Bourns"
			(at 0 0 180)
			(unlocked yes)
			(layer "F.Fab")
			(hide yes)
			(effects
				(font
					(size 1 1)
					(thickness 0.15)
				)
			)
		)
		(property "MPN" "CR0402-FX-2201GLF"
			(at 0 0 180)
			(unlocked yes)
			(layer "F.Fab")
			(hide yes)
			(effects
				(font
					(size 1 1)
					(thickness 0.15)
				)
			)
		)
		(property "Val" "2k2"
			(at 0 0 180)
			(unlocked yes)
			(layer "F.Fab")
			(hide yes)
			(effects
				(font
					(size 1 1)
					(thickness 0.15)
				)
			)
		)
		(property "License" "Apache-2.0"
			(at 0 0 180)
			(unlocked yes)
			(layer "F.Fab")
			(hide yes)
			(effects
				(font
					(size 1 1)
					(thickness 0.15)
				)
			)
		)
		(property "Author" "Antmicro"
			(at 0 0 180)
			(unlocked yes)
			(layer "F.Fab")
			(hide yes)
			(effects
				(font
					(size 1 1)
					(thickness 0.15)
				)
			)
		)
		(property "Tolerance" "1%"
			(at 0 0 180)
			(unlocked yes)
			(layer "F.Fab")
			(hide yes)
			(effects
				(font
					(size 1 1)
					(thickness 0.15)
				)
			)
		)
		(sheetname "/Compute module/")
		(sheetfile "compute-module.kicad_sch")
		(attr smd)
		(fp_rect
			(start -0.925 -0.47)
			(end 0.925 0.47)
			(stroke
				(width 0.05)
				(type default)
			)
			(fill no)
			(layer "F.CrtYd")
		)
		(fp_rect
			(start -0.5 -0.25)
			(end 0.5 0.25)
			(stroke
				(width 0.15)
				(type solid)
			)
			(fill no)
			(layer "F.Fab")
		)
		(fp_text user "Author: Antmicro"
			(at -0.95 4.169 180)
			(layer "F.Fab")
			(effects
				(font
					(size 0.7 0.7)
					(thickness 0.15)
				)
				(justify left bottom)
			)
		)
		(fp_text user "${REFERENCE}"
			(at -0.95 3.168 180)
			(layer "F.Fab")
			(effects
				(font
					(size 0.7 0.7)
					(thickness 0.15)
				)
				(justify left bottom)
			)
		)
		(fp_text user "License: Apache-2.0"
			(at -0.95 5.169 180)
			(layer "F.Fab")
			(effects
				(font
					(size 0.7 0.7)
					(thickness 0.15)
				)
				(justify left bottom)
			)
		)
		(pad "1" smd roundrect
			(at -0.48 0 180)
			(size 0.59 0.64)
			(layers "F.Cu" "F.Mask" "F.Paste")
			(roundrect_rratio 0.25)
			(net 330 "Net-(Q209-D)")
			(pintype "passive")
		)
		(pad "2" smd roundrect
			(at 0.48 0 180)
			(size 0.59 0.64)
			(layers "F.Cu" "F.Mask" "F.Paste")
			(roundrect_rratio 0.25)
			(net 255 "/Compute module/~{RPi_RST}")
			(pintype "passive")
		)
	)
)
